(kicad_pcb
	(version 20260206)
	(generator "pcbnew")
	(generator_version "10.0")
	(general
		(thickness 1.6)
		(legacy_teardrops no)
	)
	(paper "A4")
	(title_block
		(title "04192023_DAF0TMB3IC0_F0TG_MB_C_brd_V02_OCP.brd")
		(comment 1 "Grand Teton / footprints 4378-4383 of 8354")
	)
	(layers
		(0 "F.Cu" signal "TOP")
		(4 "In1.Cu" signal "GND")
		(6 "In2.Cu" signal "IN1")
		(8 "In3.Cu" signal "GND1")
		(10 "In4.Cu" signal "IN2")
		(12 "In5.Cu" signal "GND2")
		(14 "In6.Cu" signal "IN3")
		(16 "In7.Cu" signal "GND3")
		(18 "In8.Cu" signal "VCC")
		(20 "In9.Cu" signal "VCC1")
		(22 "In10.Cu" signal "GND4")
		(24 "In11.Cu" signal "IN4")
		(26 "In12.Cu" signal "GND5")
		(28 "In13.Cu" signal "IN5")
		(30 "In14.Cu" signal "GND6")
		(32 "In15.Cu" signal "IN6")
		(34 "In16.Cu" signal "GND7")
		(2 "B.Cu" signal "BOTTOM")
		(9 "F.Adhes" user "F.Adhesive")
		(11 "B.Adhes" user "B.Adhesive")
		(13 "F.Paste" user "Package Geometry/Pastemask Top")
		(15 "B.Paste" user "Package Geometry/Pastemask Bottom")
		(5 "F.SilkS" user "Ref Des/Silkscreen Top")
		(7 "B.SilkS" user "Ref Des/Silkscreen Bottom")
		(1 "F.Mask" user "Board Geometry/Soldermask Top")
		(3 "B.Mask" user "Board Geometry/Soldermask Bottom")
		(17 "Dwgs.User" user "User.Drawings")
		(19 "Cmts.User" user "User.Comments")
		(21 "Eco1.User" user "User.Eco1")
		(23 "Eco2.User" user "User.Eco2")
		(25 "Edge.Cuts" user "Board Geometry/Outline")
		(27 "Margin" user)
		(31 "F.CrtYd" user "Package Geometry/Place Bound Top")
		(29 "B.CrtYd" user "Package Geometry/Place Bound Bottom")
		(35 "F.Fab" user "Ref Des/Assembly Top")
		(33 "B.Fab" user "Ref Des/Assembly Bottom")
	)
	(footprint ""
		(layer "F.Cu")
		(at 338.324444 -381.41783 -90)
		(property "Reference" "C955"
			(at 0 0 270)
			(layer "F.SilkS")
			(hide yes)
			(effects
				(font
					(size 1.27 1.27)
				)
			)
		)
		(property "Value" ""
			(at 0 0 270)
			(layer "F.Fab")
			(effects
				(font
					(size 1.27 1.27)
				)
			)
		)
		(duplicate_pad_numbers_are_jumpers no)
		(fp_line
			(start -0.299974 0.150114)
			(end -0.299974 -0.150114)
			(stroke
				(width 0.1)
				(type default)
			)
			(layer "F.Fab")
		)
		(fp_line
			(start 0.299974 0.150114)
			(end -0.299974 0.150114)
			(stroke
				(width 0.1)
				(type default)
			)
			(layer "F.Fab")
		)
		(fp_line
			(start -0.299974 -0.150114)
			(end 0.299974 -0.150114)
			(stroke
				(width 0.1)
				(type default)
			)
			(layer "F.Fab")
		)
		(fp_line
			(start 0.299974 -0.150114)
			(end 0.299974 0.150114)
			(stroke
				(width 0.1)
				(type default)
			)
			(layer "F.Fab")
		)
		(pad "1" smd rect
			(at -0.2667 0 270)
			(size 0.3048 0.381)
			(layers "F.Cu" "F.Mask" "F.Paste")
			(net "P5E_CPU0_P1_TX_C_DP<5>")
		)
		(pad "2" smd rect
			(at 0.2667 0 270)
			(size 0.3048 0.381)
			(layers "F.Cu" "F.Mask" "F.Paste")
			(net "P5E_CPU0_P1_TX_DP<5>")
		)
	)
	(footprint ""
		(layer "F.Cu")
		(at 175.06188 -21.173948 180)
		(property "Reference" "PC2242"
			(at 0 0 180)
			(layer "F.SilkS")
			(hide yes)
			(effects
				(font
					(size 1.27 1.27)
				)
			)
		)
		(property "Value" ""
			(at 0 0 180)
			(layer "F.Fab")
			(effects
				(font
					(size 1.27 1.27)
				)
			)
		)
		(duplicate_pad_numbers_are_jumpers no)
		(fp_line
			(start 1.524 0.762)
			(end -1.524 0.762)
			(stroke
				(width 0.1524)
				(type default)
			)
			(layer "F.SilkS")
		)
		(fp_line
			(start 1.524 -0.762)
			(end 1.524 0.762)
			(stroke
				(width 0.1524)
				(type default)
			)
			(layer "F.SilkS")
		)
		(fp_line
			(start -1.524 0.762)
			(end -1.524 -0.762)
			(stroke
				(width 0.1524)
				(type default)
			)
			(layer "F.SilkS")
		)
		(fp_line
			(start -1.524 -0.762)
			(end 1.524 -0.762)
			(stroke
				(width 0.1524)
				(type default)
			)
			(layer "F.SilkS")
		)
		(fp_line
			(start 1.1049 0.724916)
			(end 1.1049 -0.724916)
			(stroke
				(width 0.1)
				(type default)
			)
			(layer "F.Fab")
		)
		(fp_line
			(start 1.1049 -0.724916)
			(end -1.1049 -0.724916)
			(stroke
				(width 0.1)
				(type default)
			)
			(layer "F.Fab")
		)
		(fp_line
			(start -1.1049 0.724916)
			(end 1.1049 0.724916)
			(stroke
				(width 0.1)
				(type default)
			)
			(layer "F.Fab")
		)
		(fp_line
			(start -1.1049 -0.724916)
			(end -1.1049 0.724916)
			(stroke
				(width 0.1)
				(type default)
			)
			(layer "F.Fab")
		)
		(pad "1" smd rect
			(at -0.889 0)
			(size 1.016 1.27)
			(layers "F.Cu" "F.Mask" "F.Paste")
			(net "P12V_SCM_R")
		)
		(pad "2" smd rect
			(at 0.889 0)
			(size 1.016 1.27)
			(layers "F.Cu" "F.Mask" "F.Paste")
			(net "GND")
		)
	)
	(footprint ""
		(layer "F.Cu")
		(at 118.11 -418.846 -90)
		(property "Reference" "R3434"
			(at 0 0 270)
			(layer "F.SilkS")
			(hide yes)
			(effects
				(font
					(size 1.27 1.27)
				)
			)
		)
		(property "Value" ""
			(at 0 0 270)
			(layer "F.Fab")
			(effects
				(font
					(size 1.27 1.27)
				)
			)
		)
		(duplicate_pad_numbers_are_jumpers no)
		(fp_line
			(start -0.7874 0.4064)
			(end -0.7874 -0.4064)
			(stroke
				(width 0.1524)
				(type default)
			)
			(layer "F.SilkS")
		)
		(fp_line
			(start 0.7874 0.4064)
			(end -0.7874 0.4064)
			(stroke
				(width 0.1524)
				(type default)
			)
			(layer "F.SilkS")
		)
		(fp_line
			(start -0.7874 -0.4064)
			(end 0.7874 -0.4064)
			(stroke
				(width 0.1524)
				(type default)
			)
			(layer "F.SilkS")
		)
		(fp_line
			(start 0.7874 -0.4064)
			(end 0.7874 0.4064)
			(stroke
				(width 0.1524)
				(type default)
			)
			(layer "F.SilkS")
		)
		(fp_line
			(start -0.67945 0.3048)
			(end -0.67945 -0.305054)
			(stroke
				(width 0.1)
				(type default)
			)
			(layer "F.Fab")
		)
		(fp_line
			(start -0.12065 0.3048)
			(end -0.67945 0.3048)
			(stroke
				(width 0.1)
				(type default)
			)
			(layer "F.Fab")
		)
		(fp_line
			(start 0.120396 0.3048)
			(end 0.120396 0.2794)
			(stroke
				(width 0.1)
				(type default)
			)
			(layer "F.Fab")
		)
		(fp_line
			(start 0.67945 0.3048)
			(end 0.120396 0.3048)
			(stroke
				(width 0.1)
				(type default)
			)
			(layer "F.Fab")
		)
		(fp_line
			(start -0.12065 0.2794)
			(end -0.12065 0.3048)
			(stroke
				(width 0.1)
				(type default)
			)
			(layer "F.Fab")
		)
		(fp_line
			(start 0.120396 0.2794)
			(end -0.12065 0.2794)
			(stroke
				(width 0.1)
				(type default)
			)
			(layer "F.Fab")
		)
		(fp_line
			(start -0.12065 -0.2794)
			(end 0.12065 -0.2794)
			(stroke
				(width 0.1)
				(type default)
			)
			(layer "F.Fab")
		)
		(fp_line
			(start 0.12065 -0.2794)
			(end 0.12065 -0.3048)
			(stroke
				(width 0.1)
				(type default)
			)
			(layer "F.Fab")
		)
		(fp_line
			(start 0.12065 -0.3048)
			(end 0.67945 -0.3048)
			(stroke
				(width 0.1)
				(type default)
			)
			(layer "F.Fab")
		)
		(fp_line
			(start 0.67945 -0.3048)
			(end 0.67945 0.3048)
			(stroke
				(width 0.1)
				(type default)
			)
			(layer "F.Fab")
		)
		(fp_line
			(start -0.67945 -0.305054)
			(end -0.12065 -0.305054)
			(stroke
				(width 0.1)
				(type default)
			)
			(layer "F.Fab")
		)
		(fp_line
			(start -0.12065 -0.305054)
			(end -0.12065 -0.2794)
			(stroke
				(width 0.1)
				(type default)
			)
			(layer "F.Fab")
		)
		(pad "1" smd circle
			(at -0.40005 0 270)
			(size 0 0)
			(layers "F.Cu" "F.Mask" "F.Paste")
			(net "P3V3_AUX")
		)
		(pad "2" smd circle
			(at 0.40005 0 270)
			(size 0 0)
			(layers "F.Cu" "F.Mask" "F.Paste")
			(net "GPU_HMC_PRSNT")
		)
	)
	(footprint ""
		(layer "F.Cu")
		(at 158.16707 -74.75347 90)
		(property "Reference" "R1005"
			(at 0 0 90)
			(layer "F.SilkS")
			(hide yes)
			(effects
				(font
					(size 1.27 1.27)
				)
			)
		)
		(property "Value" ""
			(at 0 0 90)
			(layer "F.Fab")
			(effects
				(font
					(size 1.27 1.27)
				)
			)
		)
		(duplicate_pad_numbers_are_jumpers no)
		(fp_line
			(start 0.7874 -0.4064)
			(end 0.7874 0.4064)
			(stroke
				(width 0.1524)
				(type default)
			)
			(layer "F.SilkS")
		)
		(fp_line
			(start -0.7874 -0.4064)
			(end 0.7874 -0.4064)
			(stroke
				(width 0.1524)
				(type default)
			)
			(layer "F.SilkS")
		)
		(fp_line
			(start 0.7874 0.4064)
			(end -0.7874 0.4064)
			(stroke
				(width 0.1524)
				(type default)
			)
			(layer "F.SilkS")
		)
		(fp_line
			(start -0.7874 0.4064)
			(end -0.7874 -0.4064)
			(stroke
				(width 0.1524)
				(type default)
			)
			(layer "F.SilkS")
		)
		(fp_line
			(start -0.12065 -0.305054)
			(end -0.12065 -0.2794)
			(stroke
				(width 0.1)
				(type default)
			)
			(layer "F.Fab")
		)
		(fp_line
			(start -0.67945 -0.305054)
			(end -0.12065 -0.305054)
			(stroke
				(width 0.1)
				(type default)
			)
			(layer "F.Fab")
		)
		(fp_line
			(start 0.67945 -0.3048)
			(end 0.67945 0.3048)
			(stroke
				(width 0.1)
				(type default)
			)
			(layer "F.Fab")
		)
		(fp_line
			(start 0.12065 -0.3048)
			(end 0.67945 -0.3048)
			(stroke
				(width 0.1)
				(type default)
			)
			(layer "F.Fab")
		)
		(fp_line
			(start 0.12065 -0.2794)
			(end 0.12065 -0.3048)
			(stroke
				(width 0.1)
				(type default)
			)
			(layer "F.Fab")
		)
		(fp_line
			(start -0.12065 -0.2794)
			(end 0.12065 -0.2794)
			(stroke
				(width 0.1)
				(type default)
			)
			(layer "F.Fab")
		)
		(fp_line
			(start 0.120396 0.2794)
			(end -0.12065 0.2794)
			(stroke
				(width 0.1)
				(type default)
			)
			(layer "F.Fab")
		)
		(fp_line
			(start -0.12065 0.2794)
			(end -0.12065 0.3048)
			(stroke
				(width 0.1)
				(type default)
			)
			(layer "F.Fab")
		)
		(fp_line
			(start 0.67945 0.3048)
			(end 0.120396 0.3048)
			(stroke
				(width 0.1)
				(type default)
			)
			(layer "F.Fab")
		)
		(fp_line
			(start 0.120396 0.3048)
			(end 0.120396 0.2794)
			(stroke
				(width 0.1)
				(type default)
			)
			(layer "F.Fab")
		)
		(fp_line
			(start -0.12065 0.3048)
			(end -0.67945 0.3048)
			(stroke
				(width 0.1)
				(type default)
			)
			(layer "F.Fab")
		)
		(fp_line
			(start -0.67945 0.3048)
			(end -0.67945 -0.305054)
			(stroke
				(width 0.1)
				(type default)
			)
			(layer "F.Fab")
		)
		(pad "1" smd circle
			(at -0.40005 0 90)
			(size 0 0)
			(layers "F.Cu" "F.Mask" "F.Paste")
			(net "M2_0_PEWAKE_R_N")
		)
		(pad "2" smd circle
			(at 0.40005 0 90)
			(size 0 0)
			(layers "F.Cu" "F.Mask" "F.Paste")
			(net "IRQ_LVC3_WAKE_N")
		)
	)
	(footprint ""
		(layer "F.Cu")
		(at 367.606326 -37.043868 -90)
		(property "Reference" "U116"
			(at 0.449834 -3.882136 90)
			(unlocked yes)
			(layer "F.SilkS")
			(effects
				(font
					(size 0.7874 0.5842)
					(thickness 0.1524)
				)
				(justify left)
			)
		)
		(property "Value" ""
			(at 0 0 270)
			(layer "F.Fab")
			(effects
				(font
					(size 1.27 1.27)
				)
			)
		)
		(duplicate_pad_numbers_are_jumpers no)
		(fp_line
			(start -1.868932 2.549906)
			(end 1.868932 2.549906)
			(stroke
				(width 0.1524)
				(type default)
			)
			(layer "F.SilkS")
		)
		(fp_line
			(start 1.868932 2.549906)
			(end 1.868932 -2.549906)
			(stroke
				(width 0.1524)
				(type default)
			)
			(layer "F.SilkS")
		)
		(fp_line
			(start 0 -1.524)
			(end -1.025906 -2.549906)
			(stroke
				(width 0.1524)
				(type default)
			)
			(layer "F.SilkS")
		)
		(fp_line
			(start -1.868932 -2.549906)
			(end -1.868932 2.549906)
			(stroke
				(width 0.1524)
				(type default)
			)
			(layer "F.SilkS")
		)
		(fp_line
			(start -1.025906 -2.549906)
			(end -1.868932 -2.549906)
			(stroke
				(width 0.1524)
				(type default)
			)
			(layer "F.SilkS")
		)
		(fp_line
			(start 1.025906 -2.549906)
			(end 0 -1.524)
			(stroke
				(width 0.1524)
				(type default)
			)
			(layer "F.SilkS")
		)
		(fp_line
			(start 1.868932 -2.549906)
			(end 1.025906 -2.549906)
			(stroke
				(width 0.1524)
				(type default)
			)
			(layer "F.SilkS")
		)
		(fp_poly
			(pts
				(xy -4.240276 -2.43078) (xy -5.256276 -1.92278) (xy -5.256276 -2.93878)
			)
			(stroke
				(width 0)
				(type default)
			)
			(fill yes)
			(layer "F.SilkS")
		)
		(fp_line
			(start -2.249932 2.549906)
			(end 2.249932 2.549906)
			(stroke
				(width 0.1)
				(type default)
			)
			(layer "F.Fab")
		)
		(fp_line
			(start 2.249932 2.549906)
			(end 2.249932 -2.549906)
			(stroke
				(width 0.1)
				(type default)
			)
			(layer "F.Fab")
		)
		(fp_line
			(start -2.249932 -2.549906)
			(end -2.249932 2.549906)
			(stroke
				(width 0.1)
				(type default)
			)
			(layer "F.Fab")
		)
		(fp_line
			(start 2.249932 -2.549906)
			(end -2.249932 -2.549906)
			(stroke
				(width 0.1)
				(type default)
			)
			(layer "F.Fab")
		)
		(fp_poly
			(pts
				(xy -4.7752 -1.787398) (xy -4.7752 -2.803398) (xy -3.7592 -2.295398)
			)
			(stroke
				(width 0)
				(type default)
			)
			(fill yes)
			(layer "F.Fab")
		)
		(pad "1" smd rect
			(at -2.800096 -2.275078 180)
			(size 0.3556 1.6002)
			(layers "F.Cu" "F.Mask" "F.Paste")
			(net "PVDD18_S5_P0")
		)
		(pad "2" smd rect
			(at -2.800096 -1.625092 180)
			(size 0.3556 1.6002)
			(layers "F.Cu" "F.Mask" "F.Paste")
			(net "GND")
		)
		(pad "3" smd rect
			(at -2.800096 -0.975106 180)
			(size 0.3556 1.6002)
			(layers "F.Cu" "F.Mask" "F.Paste")
			(net "UART_CPU0_SCM_UART1_TX")
		)
		(pad "4" smd rect
			(at -2.800096 -0.32512 180)
			(size 0.3556 1.6002)
			(layers "F.Cu" "F.Mask" "F.Paste")
			(net "UART_CPU0_SCM_UART1_R_RX")
		)
		(pad "5" smd rect
			(at -2.800096 0.32512 180)
			(size 0.3556 1.6002)
			(layers "F.Cu" "F.Mask" "F.Paste")
			(net "UART_CPU0_UART0_TX")
		)
		(pad "6" smd rect
			(at -2.800096 0.975106 180)
			(size 0.3556 1.6002)
			(layers "F.Cu" "F.Mask" "F.Paste")
			(net "UART_CPU0_UART0_R_RX")
		)
		(pad "7" smd rect
			(at -2.800096 1.625092 180)
			(size 0.3556 1.6002)
			(layers "F.Cu" "F.Mask" "F.Paste")
			(net "PVDD18_S5_P0")
		)
		(pad "8" smd rect
			(at -2.800096 2.275078 180)
			(size 0.3556 1.6002)
			(layers "F.Cu" "F.Mask" "F.Paste")
			(net "GND")
		)
		(pad "9" smd rect
			(at 2.800096 2.275078 180)
			(size 0.3556 1.6002)
			(layers "F.Cu" "F.Mask" "F.Paste")
			(net "UART_LS_EN_N")
		)
		(pad "10" smd rect
			(at 2.800096 1.625092 180)
			(size 0.3556 1.6002)
			(layers "F.Cu" "F.Mask" "F.Paste")
			(net "GND")
		)
		(pad "11" smd rect
			(at 2.800096 0.975106 180)
			(size 0.3556 1.6002)
			(layers "F.Cu" "F.Mask" "F.Paste")
			(net "UART_CPU0_LVC3_UART0_R_RX")
		)
		(pad "12" smd rect
			(at 2.800096 0.32512 180)
			(size 0.3556 1.6002)
			(layers "F.Cu" "F.Mask" "F.Paste")
			(net "UART_CPU0_LVC3_UART0_R_TX")
		)
		(pad "13" smd rect
			(at 2.800096 -0.32512 180)
			(size 0.3556 1.6002)
			(layers "F.Cu" "F.Mask" "F.Paste")
			(net "UART_CPU0_SCM_LVC3_UART1_R_RX")
		)
		(pad "14" smd rect
			(at 2.800096 -0.975106 180)
			(size 0.3556 1.6002)
			(layers "F.Cu" "F.Mask" "F.Paste")
			(net "UART_CPU0_SCM_LVC3_UART1_R_TX")
		)
		(pad "15" smd rect
			(at 2.800096 -1.625092 180)
			(size 0.3556 1.6002)
			(layers "F.Cu" "F.Mask" "F.Paste")
			(net "P3V3_AUX")
		)
		(pad "16" smd rect
			(at 2.800096 -2.275078 180)
			(size 0.3556 1.6002)
			(layers "F.Cu" "F.Mask" "F.Paste")
			(net "PVDD18_S5_P0")
		)
	)
	(footprint ""
		(layer "F.Cu")
		(at 215.9 -96.774 180)
		(property "Reference" "R1145"
			(at 0 0 180)
			(layer "F.SilkS")
			(hide yes)
			(effects
				(font
					(size 1.27 1.27)
				)
			)
		)
		(property "Value" ""
			(at 0 0 180)
			(layer "F.Fab")
			(effects
				(font
					(size 1.27 1.27)
				)
			)
		)
		(duplicate_pad_numbers_are_jumpers no)
		(fp_line
			(start 0.7874 0.4064)
			(end -0.7874 0.4064)
			(stroke
				(width 0.1524)
				(type default)
			)
			(layer "F.SilkS")
		)
		(fp_line
			(start 0.7874 -0.4064)
			(end 0.7874 0.4064)
			(stroke
				(width 0.1524)
				(type default)
			)
			(layer "F.SilkS")
		)
		(fp_line
			(start -0.7874 0.4064)
			(end -0.7874 -0.4064)
			(stroke
				(width 0.1524)
				(type default)
			)
			(layer "F.SilkS")
		)
		(fp_line
			(start -0.7874 -0.4064)
			(end 0.7874 -0.4064)
			(stroke
				(width 0.1524)
				(type default)
			)
			(layer "F.SilkS")
		)
		(fp_line
			(start 0.67945 0.3048)
			(end 0.120396 0.3048)
			(stroke
				(width 0.1)
				(type default)
			)
			(layer "F.Fab")
		)
		(fp_line
			(start 0.67945 -0.3048)
			(end 0.67945 0.3048)
			(stroke
				(width 0.1)
				(type default)
			)
			(layer "F.Fab")
		)
		(fp_line
			(start 0.12065 -0.2794)
			(end 0.12065 -0.3048)
			(stroke
				(width 0.1)
				(type default)
			)
			(layer "F.Fab")
		)
		(fp_line
			(start 0.12065 -0.3048)
			(end 0.67945 -0.3048)
			(stroke
				(width 0.1)
				(type default)
			)
			(layer "F.Fab")
		)
		(fp_line
			(start 0.120396 0.3048)
			(end 0.120396 0.2794)
			(stroke
				(width 0.1)
				(type default)
			)
			(layer "F.Fab")
		)
		(fp_line
			(start 0.120396 0.2794)
			(end -0.12065 0.2794)
			(stroke
				(width 0.1)
				(type default)
			)
			(layer "F.Fab")
		)
		(fp_line
			(start -0.12065 0.3048)
			(end -0.67945 0.3048)
			(stroke
				(width 0.1)
				(type default)
			)
			(layer "F.Fab")
		)
		(fp_line
			(start -0.12065 0.2794)
			(end -0.12065 0.3048)
			(stroke
				(width 0.1)
				(type default)
			)
			(layer "F.Fab")
		)
		(fp_line
			(start -0.12065 -0.2794)
			(end 0.12065 -0.2794)
			(stroke
				(width 0.1)
				(type default)
			)
			(layer "F.Fab")
		)
		(fp_line
			(start -0.12065 -0.305054)
			(end -0.12065 -0.2794)
			(stroke
				(width 0.1)
				(type default)
			)
			(layer "F.Fab")
		)
		(fp_line
			(start -0.67945 0.3048)
			(end -0.67945 -0.305054)
			(stroke
				(width 0.1)
				(type default)
			)
			(layer "F.Fab")
		)
		(fp_line
			(start -0.67945 -0.305054)
			(end -0.12065 -0.305054)
			(stroke
				(width 0.1)
				(type default)
			)
			(layer "F.Fab")
		)
		(pad "1" smd circle
			(at -0.40005 0 180)
			(size 0 0)
			(layers "F.Cu" "F.Mask" "F.Paste")
			(net "P3V3_AUX")
		)
		(pad "2" smd circle
			(at 0.40005 0 180)
			(size 0 0)
			(layers "F.Cu" "F.Mask" "F.Paste")
			(net "OCP_SFF_AUX_PWR_EN")
		)
	)
)
